(kicad_pcb
	(version 20241229)
	(generator "pcbnew")
	(generator_version "9.0")
	(general
		(thickness 1.62)
		(legacy_teardrops no)
	)
	(paper "A3")
	(title_block
		(title "COM Express 7 Baseboard")
		(date "2025-02-04")
		(rev "1.1.2")
		(company "Antmicro Ltd")
		(comment 1 "www.antmicro.com")
		(comment 9 "footprint 223 of 802 (J8), pads 1-43 of 71")
	)
	(layers
		(0 "F.Cu" signal)
		(4 "In1.Cu" signal)
		(6 "In2.Cu" signal)
		(8 "In3.Cu" signal)
		(10 "In4.Cu" signal)
		(12 "In5.Cu" signal)
		(14 "In6.Cu" signal)
		(2 "B.Cu" signal)
		(9 "F.Adhes" user "F.Adhesive")
		(11 "B.Adhes" user "B.Adhesive")
		(13 "F.Paste" user)
		(15 "B.Paste" user)
		(5 "F.SilkS" user "F.Silkscreen")
		(7 "B.SilkS" user "B.Silkscreen")
		(1 "F.Mask" user)
		(3 "B.Mask" user)
		(17 "Dwgs.User" user "User.Drawings")
		(19 "Cmts.User" user "User.Comments")
		(21 "Eco1.User" user "User.Eco1")
		(23 "Eco2.User" user "User.Eco2")
		(25 "Edge.Cuts" user)
		(27 "Margin" user)
		(31 "F.CrtYd" user "F.Courtyard")
		(29 "B.CrtYd" user "B.Courtyard")
		(35 "F.Fab" user)
		(33 "B.Fab" user)
	)
	(footprint "antmicro-footprints:Bus_M.2_Socket_Key_M_TE_1-2199230-6"
		(layer "F.Cu")
		(at 295.45 77.81)
		(property "Reference" "J8"
			(at -11.35 -5.076 0)
			(layer "F.SilkS")
			(effects
				(font
					(size 0.7 0.7)
					(thickness 0.15)
				)
				(justify left bottom)
			)
		)
		(property "Value" "Bus_M.2_1-2199230-6"
			(at -11.25 6.124 0)
			(layer "F.Fab")
			(effects
				(font
					(size 0.7 0.7)
					(thickness 0.15)
				)
				(justify left bottom)
			)
		)
		(property "Datasheet" "https://www.te.com/commerce/DocumentDelivery/DDEController?Action=srchrtrv&DocNm=2199230&DocType=Customer+Drawing&DocLang=English"
			(at 0 0 0)
			(layer "F.Fab")
			(hide yes)
			(effects
				(font
					(size 1.27 1.27)
					(thickness 0.15)
				)
			)
		)
		(property "Author" "Antmicro"
			(at 0 0 0)
			(layer "F.Fab")
			(hide yes)
			(effects
				(font
					(size 1 1)
					(thickness 0.15)
				)
			)
		)
		(property "License" "Apache-2.0"
			(at 0 0 0)
			(layer "F.Fab")
			(hide yes)
			(effects
				(font
					(size 1 1)
					(thickness 0.15)
				)
			)
		)
		(property "MPN" "1-2199230-6"
			(at 0 0 0)
			(layer "F.Fab")
			(hide yes)
			(effects
				(font
					(size 1 1)
					(thickness 0.15)
				)
			)
		)
		(property "Manufacturer" "TE Connectivity"
			(at 0 0 0)
			(layer "F.Fab")
			(hide yes)
			(effects
				(font
					(size 1 1)
					(thickness 0.15)
				)
			)
		)
		(sheetname "M.2 key M #2")
		(sheetfile "m2keym.kicad_sch")
		(attr smd)
		(pad "" np_thru_hole circle
			(at -10 1.499)
			(size 1.1 1.1)
			(drill 1.1)
			(layers "*.Mask")
		)
		(pad "" np_thru_hole circle
			(at 9.997 1.499)
			(size 1.6 1.6)
			(drill 1.6)
			(layers "*.Mask")
		)
		(pad "1" smd rect
			(at -9.25 -3.775)
			(size 0.3 1.55)
			(layers "F.Cu" "F.Mask" "F.Paste")
			(net 1 "GND")
			(pinfunction "GND")
			(pintype "power_in")
			(teardrops
				(best_length_ratio 0.2)
				(max_length 1)
				(best_width_ratio 0.9)
				(max_width 2)
				(curved_edges yes)
				(filter_ratio 0.9)
				(enabled yes)
				(allow_two_segments yes)
				(prefer_zone_connections yes)
			)
		)
		(pad "2" smd rect
			(at -9.003 3.773)
			(size 0.3 1.55)
			(layers "F.Cu" "F.Mask" "F.Paste")
			(net 970 "/M.2 key M #2/M2_3V3")
			(pinfunction "3V3")
			(pintype "passive")
			(teardrops
				(best_length_ratio 0.2)
				(max_length 1)
				(best_width_ratio 0.9)
				(max_width 2)
				(curved_edges yes)
				(filter_ratio 0.9)
				(enabled yes)
				(allow_two_segments yes)
				(prefer_zone_connections yes)
			)
		)
		(pad "3" smd rect
			(at -8.753 -3.775)
			(size 0.3 1.55)
			(layers "F.Cu" "F.Mask" "F.Paste")
			(net 1 "GND")
			(pinfunction "GND")
			(pintype "passive")
			(teardrops
				(best_length_ratio 0.2)
				(max_length 1)
				(best_width_ratio 0.9)
				(max_width 2)
				(curved_edges yes)
				(filter_ratio 0.9)
				(enabled yes)
				(allow_two_segments yes)
				(prefer_zone_connections yes)
			)
		)
		(pad "4" smd rect
			(at -8.503 3.773)
			(size 0.3 1.55)
			(layers "F.Cu" "F.Mask" "F.Paste")
			(net 970 "/M.2 key M #2/M2_3V3")
			(pinfunction "3V3")
			(pintype "passive")
			(teardrops
				(best_length_ratio 0.2)
				(max_length 1)
				(best_width_ratio 0.9)
				(max_width 2)
				(curved_edges yes)
				(filter_ratio 0.9)
				(enabled yes)
				(allow_two_segments yes)
				(prefer_zone_connections yes)
			)
		)
		(pad "5" smd rect
			(at -8.253 -3.775)
			(size 0.3 1.55)
			(layers "F.Cu" "F.Mask" "F.Paste")
			(net 93 "/Com Express 7 Interfaces/PCIe_{B2Ax4}.RX3+")
			(pinfunction "PER3_N")
			(pintype "output")
			(teardrops
				(best_length_ratio 0.2)
				(max_length 1)
				(best_width_ratio 0.9)
				(max_width 2)
				(curved_edges yes)
				(filter_ratio 0.9)
				(enabled yes)
				(allow_two_segments yes)
				(prefer_zone_connections yes)
			)
		)
		(pad "6" smd rect
			(at -8.001 3.773)
			(size 0.3 1.55)
			(layers "F.Cu" "F.Mask" "F.Paste")
			(net 238 "unconnected-(J8-NC-Pad6)")
			(pinfunction "NC")
			(pintype "no_connect")
			(teardrops
				(best_length_ratio 0.2)
				(max_length 1)
				(best_width_ratio 0.9)
				(max_width 2)
				(curved_edges yes)
				(filter_ratio 0.9)
				(enabled yes)
				(allow_two_segments yes)
				(prefer_zone_connections yes)
			)
		)
		(pad "7" smd rect
			(at -7.752 -3.775)
			(size 0.3 1.55)
			(layers "F.Cu" "F.Mask" "F.Paste")
			(net 89 "/Com Express 7 Interfaces/PCIe_{B2Ax4}.RX3-")
			(pinfunction "PER3_P")
			(pintype "output")
			(teardrops
				(best_length_ratio 0.2)
				(max_length 1)
				(best_width_ratio 0.9)
				(max_width 2)
				(curved_edges yes)
				(filter_ratio 0.9)
				(enabled yes)
				(allow_two_segments yes)
				(prefer_zone_connections yes)
			)
		)
		(pad "8" smd rect
			(at -7.502 3.773)
			(size 0.3 1.55)
			(layers "F.Cu" "F.Mask" "F.Paste")
			(net 240 "unconnected-(J8-NC-Pad8)")
			(pinfunction "NC")
			(pintype "no_connect")
			(teardrops
				(best_length_ratio 0.2)
				(max_length 1)
				(best_width_ratio 0.9)
				(max_width 2)
				(curved_edges yes)
				(filter_ratio 0.9)
				(enabled yes)
				(allow_two_segments yes)
				(prefer_zone_connections yes)
			)
		)
		(pad "9" smd rect
			(at -7.252 -3.775)
			(size 0.3 1.55)
			(layers "F.Cu" "F.Mask" "F.Paste")
			(net 1 "GND")
			(pinfunction "GND")
			(pintype "passive")
			(teardrops
				(best_length_ratio 0.2)
				(max_length 1)
				(best_width_ratio 0.9)
				(max_width 2)
				(curved_edges yes)
				(filter_ratio 0.9)
				(enabled yes)
				(allow_two_segments yes)
				(prefer_zone_connections yes)
			)
		)
		(pad "10" smd rect
			(at -7.002 3.773)
			(size 0.3 1.55)
			(layers "F.Cu" "F.Mask" "F.Paste")
			(net 936 "Net-(D14-C)")
			(pinfunction "LED")
			(pintype "passive")
			(teardrops
				(best_length_ratio 0.2)
				(max_length 1)
				(best_width_ratio 0.9)
				(max_width 2)
				(curved_edges yes)
				(filter_ratio 0.9)
				(enabled yes)
				(allow_two_segments yes)
				(prefer_zone_connections yes)
			)
		)
		(pad "11" smd rect
			(at -6.752 -3.775)
			(size 0.3 1.55)
			(layers "F.Cu" "F.Mask" "F.Paste")
			(net 330 "/Com Express 7 Interfaces/PCIe_{B2Ax4}.TX3+")
			(pinfunction "PET3_N")
			(pintype "input")
			(teardrops
				(best_length_ratio 0.2)
				(max_length 1)
				(best_width_ratio 0.9)
				(max_width 2)
				(curved_edges yes)
				(filter_ratio 0.9)
				(enabled yes)
				(allow_two_segments yes)
				(prefer_zone_connections yes)
			)
		)
		(pad "12" smd rect
			(at -6.502 3.773)
			(size 0.3 1.55)
			(layers "F.Cu" "F.Mask" "F.Paste")
			(net 970 "/M.2 key M #2/M2_3V3")
			(pinfunction "3V3")
			(pintype "passive")
			(teardrops
				(best_length_ratio 0.2)
				(max_length 1)
				(best_width_ratio 0.9)
				(max_width 2)
				(curved_edges yes)
				(filter_ratio 0.9)
				(enabled yes)
				(allow_two_segments yes)
				(prefer_zone_connections yes)
			)
		)
		(pad "13" smd rect
			(at -6.252 -3.775)
			(size 0.3 1.55)
			(layers "F.Cu" "F.Mask" "F.Paste")
			(net 331 "/Com Express 7 Interfaces/PCIe_{B2Ax4}.TX3-")
			(pinfunction "PET3_P")
			(pintype "input")
			(teardrops
				(best_length_ratio 0.2)
				(max_length 1)
				(best_width_ratio 0.9)
				(max_width 2)
				(curved_edges yes)
				(filter_ratio 0.9)
				(enabled yes)
				(allow_two_segments yes)
				(prefer_zone_connections yes)
			)
		)
		(pad "14" smd rect
			(at -6.002 3.773)
			(size 0.3 1.55)
			(layers "F.Cu" "F.Mask" "F.Paste")
			(net 970 "/M.2 key M #2/M2_3V3")
			(pinfunction "3V3")
			(pintype "passive")
			(teardrops
				(best_length_ratio 0.2)
				(max_length 1)
				(best_width_ratio 0.9)
				(max_width 2)
				(curved_edges yes)
				(filter_ratio 0.9)
				(enabled yes)
				(allow_two_segments yes)
				(prefer_zone_connections yes)
			)
		)
		(pad "15" smd rect
			(at -5.752 -3.775)
			(size 0.3 1.55)
			(layers "F.Cu" "F.Mask" "F.Paste")
			(net 1 "GND")
			(pinfunction "GND")
			(pintype "passive")
			(teardrops
				(best_length_ratio 0.2)
				(max_length 1)
				(best_width_ratio 0.9)
				(max_width 2)
				(curved_edges yes)
				(filter_ratio 0.9)
				(enabled yes)
				(allow_two_segments yes)
				(prefer_zone_connections yes)
			)
		)
		(pad "16" smd rect
			(at -5.502 3.773)
			(size 0.3 1.55)
			(layers "F.Cu" "F.Mask" "F.Paste")
			(net 970 "/M.2 key M #2/M2_3V3")
			(pinfunction "3V3")
			(pintype "passive")
			(teardrops
				(best_length_ratio 0.2)
				(max_length 1)
				(best_width_ratio 0.9)
				(max_width 2)
				(curved_edges yes)
				(filter_ratio 0.9)
				(enabled yes)
				(allow_two_segments yes)
				(prefer_zone_connections yes)
			)
		)
		(pad "17" smd rect
			(at -5.252 -3.775)
			(size 0.3 1.55)
			(layers "F.Cu" "F.Mask" "F.Paste")
			(net 92 "/Com Express 7 Interfaces/PCIe_{B2Ax4}.RX2+")
			(pinfunction "PER2_N")
			(pintype "output")
			(teardrops
				(best_length_ratio 0.2)
				(max_length 1)
				(best_width_ratio 0.9)
				(max_width 2)
				(curved_edges yes)
				(filter_ratio 0.9)
				(enabled yes)
				(allow_two_segments yes)
				(prefer_zone_connections yes)
			)
		)
		(pad "18" smd rect
			(at -5.002 3.773)
			(size 0.3 1.55)
			(layers "F.Cu" "F.Mask" "F.Paste")
			(net 970 "/M.2 key M #2/M2_3V3")
			(pinfunction "3V3")
			(pintype "passive")
			(teardrops
				(best_length_ratio 0.2)
				(max_length 1)
				(best_width_ratio 0.9)
				(max_width 2)
				(curved_edges yes)
				(filter_ratio 0.9)
				(enabled yes)
				(allow_two_segments yes)
				(prefer_zone_connections yes)
			)
		)
		(pad "19" smd rect
			(at -4.752 -3.775)
			(size 0.3 1.55)
			(layers "F.Cu" "F.Mask" "F.Paste")
			(net 88 "/Com Express 7 Interfaces/PCIe_{B2Ax4}.RX2-")
			(pinfunction "PER2_P")
			(pintype "output")
			(teardrops
				(best_length_ratio 0.2)
				(max_length 1)
				(best_width_ratio 0.9)
				(max_width 2)
				(curved_edges yes)
				(filter_ratio 0.9)
				(enabled yes)
				(allow_two_segments yes)
				(prefer_zone_connections yes)
			)
		)
		(pad "20" smd rect
			(at -4.502 3.773)
			(size 0.3 1.55)
			(layers "F.Cu" "F.Mask" "F.Paste")
			(net 245 "unconnected-(J8-NC-Pad20)")
			(pinfunction "NC")
			(pintype "no_connect")
			(teardrops
				(best_length_ratio 0.2)
				(max_length 1)
				(best_width_ratio 0.9)
				(max_width 2)
				(curved_edges yes)
				(filter_ratio 0.9)
				(enabled yes)
				(allow_two_segments yes)
				(prefer_zone_connections yes)
			)
		)
		(pad "21" smd rect
			(at -4.252 -3.775)
			(size 0.3 1.55)
			(layers "F.Cu" "F.Mask" "F.Paste")
			(net 1 "GND")
			(pinfunction "GND")
			(pintype "passive")
			(teardrops
				(best_length_ratio 0.2)
				(max_length 1)
				(best_width_ratio 0.9)
				(max_width 2)
				(curved_edges yes)
				(filter_ratio 0.9)
				(enabled yes)
				(allow_two_segments yes)
				(prefer_zone_connections yes)
			)
		)
		(pad "22" smd rect
			(at -4.002 3.773)
			(size 0.3 1.55)
			(layers "F.Cu" "F.Mask" "F.Paste")
			(net 246 "unconnected-(J8-NC-Pad22)")
			(pinfunction "NC")
			(pintype "no_connect")
			(teardrops
				(best_length_ratio 0.2)
				(max_length 1)
				(best_width_ratio 0.9)
				(max_width 2)
				(curved_edges yes)
				(filter_ratio 0.9)
				(enabled yes)
				(allow_two_segments yes)
				(prefer_zone_connections yes)
			)
		)
		(pad "23" smd rect
			(at -3.751 -3.775)
			(size 0.3 1.55)
			(layers "F.Cu" "F.Mask" "F.Paste")
			(net 328 "/Com Express 7 Interfaces/PCIe_{B2Ax4}.TX2+")
			(pinfunction "PET2_N")
			(pintype "input")
			(teardrops
				(best_length_ratio 0.2)
				(max_length 1)
				(best_width_ratio 0.9)
				(max_width 2)
				(curved_edges yes)
				(filter_ratio 0.9)
				(enabled yes)
				(allow_two_segments yes)
				(prefer_zone_connections yes)
			)
		)
		(pad "24" smd rect
			(at -3.501 3.773)
			(size 0.3 1.55)
			(layers "F.Cu" "F.Mask" "F.Paste")
			(net 248 "unconnected-(J8-NC-Pad24)")
			(pinfunction "NC")
			(pintype "no_connect")
			(teardrops
				(best_length_ratio 0.2)
				(max_length 1)
				(best_width_ratio 0.9)
				(max_width 2)
				(curved_edges yes)
				(filter_ratio 0.9)
				(enabled yes)
				(allow_two_segments yes)
				(prefer_zone_connections yes)
			)
		)
		(pad "25" smd rect
			(at -3.251 -3.775)
			(size 0.3 1.55)
			(layers "F.Cu" "F.Mask" "F.Paste")
			(net 329 "/Com Express 7 Interfaces/PCIe_{B2Ax4}.TX2-")
			(pinfunction "PET2_P")
			(pintype "input")
			(teardrops
				(best_length_ratio 0.2)
				(max_length 1)
				(best_width_ratio 0.9)
				(max_width 2)
				(curved_edges yes)
				(filter_ratio 0.9)
				(enabled yes)
				(allow_two_segments yes)
				(prefer_zone_connections yes)
			)
		)
		(pad "26" smd rect
			(at -3.001 3.773)
			(size 0.3 1.55)
			(layers "F.Cu" "F.Mask" "F.Paste")
			(net 250 "unconnected-(J8-NC-Pad26)")
			(pinfunction "NC")
			(pintype "no_connect")
			(teardrops
				(best_length_ratio 0.2)
				(max_length 1)
				(best_width_ratio 0.9)
				(max_width 2)
				(curved_edges yes)
				(filter_ratio 0.9)
				(enabled yes)
				(allow_two_segments yes)
				(prefer_zone_connections yes)
			)
		)
		(pad "27" smd rect
			(at -2.751 -3.775)
			(size 0.3 1.55)
			(layers "F.Cu" "F.Mask" "F.Paste")
			(net 1 "GND")
			(pinfunction "GND")
			(pintype "passive")
			(teardrops
				(best_length_ratio 0.2)
				(max_length 1)
				(best_width_ratio 0.9)
				(max_width 2)
				(curved_edges yes)
				(filter_ratio 0.9)
				(enabled yes)
				(allow_two_segments yes)
				(prefer_zone_connections yes)
			)
		)
		(pad "28" smd rect
			(at -2.501 3.773)
			(size 0.3 1.55)
			(layers "F.Cu" "F.Mask" "F.Paste")
			(net 251 "unconnected-(J8-NC-Pad28)")
			(pinfunction "NC")
			(pintype "no_connect")
			(teardrops
				(best_length_ratio 0.2)
				(max_length 1)
				(best_width_ratio 0.9)
				(max_width 2)
				(curved_edges yes)
				(filter_ratio 0.9)
				(enabled yes)
				(allow_two_segments yes)
				(prefer_zone_connections yes)
			)
		)
		(pad "29" smd rect
			(at -2.251 -3.775)
			(size 0.3 1.55)
			(layers "F.Cu" "F.Mask" "F.Paste")
			(net 91 "/Com Express 7 Interfaces/PCIe_{B2Ax4}.RX1+")
			(pinfunction "PER1_N")
			(pintype "output")
			(teardrops
				(best_length_ratio 0.2)
				(max_length 1)
				(best_width_ratio 0.9)
				(max_width 2)
				(curved_edges yes)
				(filter_ratio 0.9)
				(enabled yes)
				(allow_two_segments yes)
				(prefer_zone_connections yes)
			)
		)
		(pad "30" smd rect
			(at -2.001 3.773)
			(size 0.3 1.55)
			(layers "F.Cu" "F.Mask" "F.Paste")
			(net 253 "unconnected-(J8-NC-Pad30)")
			(pinfunction "NC")
			(pintype "no_connect")
			(teardrops
				(best_length_ratio 0.2)
				(max_length 1)
				(best_width_ratio 0.9)
				(max_width 2)
				(curved_edges yes)
				(filter_ratio 0.9)
				(enabled yes)
				(allow_two_segments yes)
				(prefer_zone_connections yes)
			)
		)
		(pad "31" smd rect
			(at -1.752 -3.775)
			(size 0.3 1.55)
			(layers "F.Cu" "F.Mask" "F.Paste")
			(net 87 "/Com Express 7 Interfaces/PCIe_{B2Ax4}.RX1-")
			(pinfunction "PER1_P")
			(pintype "output")
			(teardrops
				(best_length_ratio 0.2)
				(max_length 1)
				(best_width_ratio 0.9)
				(max_width 2)
				(curved_edges yes)
				(filter_ratio 0.9)
				(enabled yes)
				(allow_two_segments yes)
				(prefer_zone_connections yes)
			)
		)
		(pad "32" smd rect
			(at -1.502 3.773)
			(size 0.3 1.55)
			(layers "F.Cu" "F.Mask" "F.Paste")
			(net 255 "unconnected-(J8-NC-Pad32)")
			(pinfunction "NC")
			(pintype "no_connect")
			(teardrops
				(best_length_ratio 0.2)
				(max_length 1)
				(best_width_ratio 0.9)
				(max_width 2)
				(curved_edges yes)
				(filter_ratio 0.9)
				(enabled yes)
				(allow_two_segments yes)
				(prefer_zone_connections yes)
			)
		)
		(pad "33" smd rect
			(at -1.252 -3.775)
			(size 0.3 1.55)
			(layers "F.Cu" "F.Mask" "F.Paste")
			(net 1 "GND")
			(pinfunction "GND")
			(pintype "passive")
			(teardrops
				(best_length_ratio 0.2)
				(max_length 1)
				(best_width_ratio 0.9)
				(max_width 2)
				(curved_edges yes)
				(filter_ratio 0.9)
				(enabled yes)
				(allow_two_segments yes)
				(prefer_zone_connections yes)
			)
		)
		(pad "34" smd rect
			(at -1.002 3.773)
			(size 0.3 1.55)
			(layers "F.Cu" "F.Mask" "F.Paste")
			(net 256 "unconnected-(J8-NC-Pad34)")
			(pinfunction "NC")
			(pintype "no_connect")
			(teardrops
				(best_length_ratio 0.2)
				(max_length 1)
				(best_width_ratio 0.9)
				(max_width 2)
				(curved_edges yes)
				(filter_ratio 0.9)
				(enabled yes)
				(allow_two_segments yes)
				(prefer_zone_connections yes)
			)
		)
		(pad "35" smd rect
			(at -0.751 -3.775)
			(size 0.3 1.55)
			(layers "F.Cu" "F.Mask" "F.Paste")
			(net 326 "/Com Express 7 Interfaces/PCIe_{B2Ax4}.TX1+")
			(pinfunction "PET1_N")
			(pintype "input")
			(teardrops
				(best_length_ratio 0.2)
				(max_length 1)
				(best_width_ratio 0.9)
				(max_width 2)
				(curved_edges yes)
				(filter_ratio 0.9)
				(enabled yes)
				(allow_two_segments yes)
				(prefer_zone_connections yes)
			)
		)
		(pad "36" smd rect
			(at -0.501 3.773)
			(size 0.3 1.55)
			(layers "F.Cu" "F.Mask" "F.Paste")
			(net 258 "unconnected-(J8-NC-Pad36)")
			(pinfunction "NC")
			(pintype "no_connect")
			(teardrops
				(best_length_ratio 0.2)
				(max_length 1)
				(best_width_ratio 0.9)
				(max_width 2)
				(curved_edges yes)
				(filter_ratio 0.9)
				(enabled yes)
				(allow_two_segments yes)
				(prefer_zone_connections yes)
			)
		)
		(pad "37" smd rect
			(at -0.251 -3.775)
			(size 0.3 1.55)
			(layers "F.Cu" "F.Mask" "F.Paste")
			(net 327 "/Com Express 7 Interfaces/PCIe_{B2Ax4}.TX1-")
			(pinfunction "PET1_P")
			(pintype "input")
			(teardrops
				(best_length_ratio 0.2)
				(max_length 1)
				(best_width_ratio 0.9)
				(max_width 2)
				(curved_edges yes)
				(filter_ratio 0.9)
				(enabled yes)
				(allow_two_segments yes)
				(prefer_zone_connections yes)
			)
		)
		(pad "38" smd rect
			(at -0.001 3.773)
			(size 0.3 1.55)
			(layers "F.Cu" "F.Mask" "F.Paste")
			(net 260 "unconnected-(J8-NC-Pad38)")
			(pinfunction "NC")
			(pintype "no_connect")
			(teardrops
				(best_length_ratio 0.2)
				(max_length 1)
				(best_width_ratio 0.9)
				(max_width 2)
				(curved_edges yes)
				(filter_ratio 0.9)
				(enabled yes)
				(allow_two_segments yes)
				(prefer_zone_connections yes)
			)
		)
		(pad "39" smd rect
			(at 0.248 -3.775)
			(size 0.3 1.55)
			(layers "F.Cu" "F.Mask" "F.Paste")
			(net 1 "GND")
			(pinfunction "GND")
			(pintype "passive")
			(teardrops
				(best_length_ratio 0.2)
				(max_length 1)
				(best_width_ratio 0.9)
				(max_width 2)
				(curved_edges yes)
				(filter_ratio 0.9)
				(enabled yes)
				(allow_two_segments yes)
				(prefer_zone_connections yes)
			)
		)
		(pad "40" smd rect
			(at 0.498 3.773)
			(size 0.3 1.55)
			(layers "F.Cu" "F.Mask" "F.Paste")
			(net 261 "unconnected-(J8-SMB_CLK-Pad40)")
			(pinfunction "SMB_CLK")
			(pintype "input+no_connect")
			(teardrops
				(best_length_ratio 0.2)
				(max_length 1)
				(best_width_ratio 0.9)
				(max_width 2)
				(curved_edges yes)
				(filter_ratio 0.9)
				(enabled yes)
				(allow_two_segments yes)
				(prefer_zone_connections yes)
			)
		)
		(pad "41" smd rect
			(at 0.748 -3.775)
			(size 0.3 1.55)
			(layers "F.Cu" "F.Mask" "F.Paste")
			(net 90 "/Com Express 7 Interfaces/PCIe_{B2Ax4}.RX0+")
			(pinfunction "PER0_N")
			(pintype "output")
			(teardrops
				(best_length_ratio 0.2)
				(max_length 1)
				(best_width_ratio 0.9)
				(max_width 2)
				(curved_edges yes)
				(filter_ratio 0.9)
				(enabled yes)
				(allow_two_segments yes)
				(prefer_zone_connections yes)
			)
		)
	)
)
